# S9S_MB_2U (Grand Teton) — schematic netlist excerpt (pin names and nets, part order shuffled) for the footprints in the layout excerpt that follows; sources: Cadence DE-HDL packaged netlist, KiCad conversion of 03242023_DA0F0TMBIJ0_F0T_Motherboard_J_brd_V01_OCP.brd

PR3931  Q_RES  75K 0.1% CHIP  pkg 0402LF  page 301 : A = P12V_AUX ; B = HSC_VOSEN
D145  Q_DIODE  SDMK0340L-7-F IC  pkg SMLF  page 259 : \1\ = MB0_P12V_STBY_PWRGD ; \2\ = P3V3_AUX_EN

(kicad_pcb
	(version 20260206)
	(generator "pcbnew")
	(generator_version "10.0")
	(general
		(thickness 1.6)
		(legacy_teardrops no)
	)
	(paper "A4")
	(title_block
		(title "03242023_DA0F0TMBIJ0_F0T_Motherboard_J_brd_V01_OCP.brd")
		(comment 1 "Grand Teton / footprints 4226-4227 of 6105")
	)
	(layers
		(0 "F.Cu" signal "TOP")
		(4 "In1.Cu" signal "GND")
		(6 "In2.Cu" signal "IN1")
		(8 "In3.Cu" signal "GND1")
		(10 "In4.Cu" signal "IN2")
		(12 "In5.Cu" signal "GND2")
		(14 "In6.Cu" signal "IN3")
		(16 "In7.Cu" signal "GND3")
		(18 "In8.Cu" signal "VCC")
		(20 "In9.Cu" signal "VCC1")
		(22 "In10.Cu" signal "GND4")
		(24 "In11.Cu" signal "IN4")
		(26 "In12.Cu" signal "GND5")
		(28 "In13.Cu" signal "IN5")
		(30 "In14.Cu" signal "GND6")
		(32 "In15.Cu" signal "IN6")
		(34 "In16.Cu" signal "GND7")
		(2 "B.Cu" signal "BOTTOM")
		(9 "F.Adhes" user "F.Adhesive")
		(11 "B.Adhes" user "B.Adhesive")
		(13 "F.Paste" user "Package Geometry/Pastemask Top")
		(15 "B.Paste" user "Package Geometry/Pastemask Bottom")
		(5 "F.SilkS" user "Ref Des/Silkscreen Top")
		(7 "B.SilkS" user "Ref Des/Silkscreen Bottom")
		(1 "F.Mask" user "Board Geometry/Soldermask Top")
		(3 "B.Mask" user "Board Geometry/Soldermask Bottom")
		(17 "Dwgs.User" user "User.Drawings")
		(19 "Cmts.User" user "User.Comments")
		(21 "Eco1.User" user "User.Eco1")
		(23 "Eco2.User" user "User.Eco2")
		(25 "Edge.Cuts" user "Board Geometry/Outline")
		(27 "Margin" user)
		(31 "F.CrtYd" user "Package Geometry/Place Bound Top")
		(29 "B.CrtYd" user "Package Geometry/Place Bound Bottom")
		(35 "F.Fab" user "Ref Des/Assembly Top")
		(33 "B.Fab" user "Ref Des/Assembly Bottom")
	)
	(footprint ""
		(layer "B.Cu")
		(at 452.247 -81.031842 -90)
		(property "Reference" "D145"
			(at 1.205484 -1.580642 270)
			(unlocked yes)
			(layer "B.SilkS")
			(effects
				(font
					(size 0.7874 0.5842)
					(thickness 0.1524)
				)
				(justify left mirror)
			)
		)
		(property "Value" ""
			(at 0 0 90)
			(layer "B.Fab")
			(effects
				(font
					(size 1.27 1.27)
				)
				(justify mirror)
			)
		)
		(duplicate_pad_numbers_are_jumpers no)
		(fp_line
			(start -2.050796 0.700024)
			(end 2.050796 0.700024)
			(stroke
				(width 0.1524)
				(type default)
			)
			(layer "B.SilkS")
		)
		(fp_line
			(start 2.050796 0.700024)
			(end 2.050796 -0.700024)
			(stroke
				(width 0.1524)
				(type default)
			)
			(layer "B.SilkS")
		)
		(fp_line
			(start -2.343404 0.6985)
			(end -2.216404 0.6985)
			(stroke
				(width 0.1524)
				(type default)
			)
			(layer "B.SilkS")
		)
		(fp_line
			(start -2.229104 0.6985)
			(end -2.051304 0.6985)
			(stroke
				(width 0.1524)
				(type default)
			)
			(layer "B.SilkS")
		)
		(fp_line
			(start -2.051304 0.6985)
			(end -2.051304 0.635)
			(stroke
				(width 0.1524)
				(type default)
			)
			(layer "B.SilkS")
		)
		(fp_line
			(start -2.152904 0.635)
			(end -2.152904 -0.6985)
			(stroke
				(width 0.1524)
				(type default)
			)
			(layer "B.SilkS")
		)
		(fp_line
			(start -2.051304 0.635)
			(end -2.152904 0.635)
			(stroke
				(width 0.1524)
				(type default)
			)
			(layer "B.SilkS")
		)
		(fp_line
			(start 0.30607 0.500126)
			(end -0.193802 0)
			(stroke
				(width 0.1524)
				(type default)
			)
			(layer "B.SilkS")
		)
		(fp_line
			(start -0.193802 0)
			(end 0.30607 -0.500126)
			(stroke
				(width 0.1524)
				(type default)
			)
			(layer "B.SilkS")
		)
		(fp_line
			(start -0.293878 -0.500126)
			(end -0.293878 0.500126)
			(stroke
				(width 0.1524)
				(type default)
			)
			(layer "B.SilkS")
		)
		(fp_line
			(start 0.30607 -0.500126)
			(end 0.30607 0.500126)
			(stroke
				(width 0.1524)
				(type default)
			)
			(layer "B.SilkS")
		)
		(fp_line
			(start -2.064004 -0.6731)
			(end -2.064004 -0.6985)
			(stroke
				(width 0.1524)
				(type default)
			)
			(layer "B.SilkS")
		)
		(fp_line
			(start -2.343404 -0.6985)
			(end -2.343404 0.6985)
			(stroke
				(width 0.1524)
				(type default)
			)
			(layer "B.SilkS")
		)
		(fp_line
			(start -2.229104 -0.6985)
			(end -2.229104 0.6985)
			(stroke
				(width 0.1524)
				(type default)
			)
			(layer "B.SilkS")
		)
		(fp_line
			(start -2.152904 -0.6985)
			(end -2.343404 -0.6985)
			(stroke
				(width 0.1524)
				(type default)
			)
			(layer "B.SilkS")
		)
		(fp_line
			(start -2.064004 -0.6985)
			(end -2.229104 -0.6985)
			(stroke
				(width 0.1524)
				(type default)
			)
			(layer "B.SilkS")
		)
		(fp_line
			(start -2.050796 -0.700024)
			(end -2.050796 0.700024)
			(stroke
				(width 0.1524)
				(type default)
			)
			(layer "B.SilkS")
		)
		(fp_line
			(start 2.050796 -0.700024)
			(end -2.050796 -0.700024)
			(stroke
				(width 0.1524)
				(type default)
			)
			(layer "B.SilkS")
		)
		(fp_line
			(start -0.899922 0.700024)
			(end 0.899922 0.700024)
			(stroke
				(width 0.1)
				(type default)
			)
			(layer "B.Fab")
		)
		(fp_line
			(start 0.899922 0.700024)
			(end 0.899922 -0.700024)
			(stroke
				(width 0.1)
				(type default)
			)
			(layer "B.Fab")
		)
		(fp_line
			(start -0.899922 -0.700024)
			(end -0.899922 0.700024)
			(stroke
				(width 0.1)
				(type default)
			)
			(layer "B.Fab")
		)
		(fp_line
			(start 0.899922 -0.700024)
			(end -0.899922 -0.700024)
			(stroke
				(width 0.1)
				(type default)
			)
			(layer "B.Fab")
		)
		(fp_text user "+"
			(at 3.220466 -0.241046 180)
			(unlocked yes)
			(layer "B.SilkS")
			(effects
				(font
					(size 1.905 1.4224)
					(thickness 0.1524)
				)
				(justify left mirror)
			)
		)
		(fp_text user "-"
			(at -3.95732 -0.652526 90)
			(unlocked yes)
			(layer "B.SilkS")
			(effects
				(font
					(size 1.905 1.4224)
					(thickness 0.1524)
				)
				(justify left mirror)
			)
		)
		(fp_text user "+"
			(at 3.123946 0.762 180)
			(unlocked yes)
			(layer "B.Fab")
			(effects
				(font
					(size 1.905 1.4224)
					(thickness 0.1524)
				)
				(justify left mirror)
			)
		)
		(fp_text user "-"
			(at -3.880104 0.23495 90)
			(unlocked yes)
			(layer "B.Fab")
			(effects
				(font
					(size 1.905 1.4224)
					(thickness 0.1524)
				)
				(justify left mirror)
			)
		)
		(pad "1" smd rect
			(at 1.199896 0 180)
			(size 0.6604 1.3716)
			(layers "B.Cu" "B.Mask" "B.Paste")
			(net "MB0_P12V_STBY_PWRGD")
		)
		(pad "2" smd rect
			(at -1.199896 0)
			(size 0.6604 1.3716)
			(layers "B.Cu" "B.Mask" "B.Paste")
			(net "P3V3_AUX_EN")
		)
	)
	(footprint ""
		(layer "B.Cu")
		(at 184.976008 -398.651222)
		(property "Reference" "PR3931"
			(at 0 0 0)
			(layer "B.SilkS")
			(hide yes)
			(effects
				(font
					(size 1.27 1.27)
				)
				(justify mirror)
			)
		)
		(property "Value" ""
			(at 0 0 0)
			(layer "B.Fab")
			(effects
				(font
					(size 1.27 1.27)
				)
				(justify mirror)
			)
		)
		(duplicate_pad_numbers_are_jumpers no)
		(fp_line
			(start -0.7874 -0.4064)
			(end -0.7874 0.4064)
			(stroke
				(width 0.1524)
				(type default)
			)
			(layer "B.SilkS")
		)
		(fp_line
			(start -0.7874 0.4064)
			(end 0.7874 0.4064)
			(stroke
				(width 0.1524)
				(type default)
			)
			(layer "B.SilkS")
		)
		(fp_line
			(start 0.7874 -0.4064)
			(end -0.7874 -0.4064)
			(stroke
				(width 0.1524)
				(type default)
			)
			(layer "B.SilkS")
		)
		(fp_line
			(start 0.7874 0.4064)
			(end 0.7874 -0.4064)
			(stroke
				(width 0.1524)
				(type default)
			)
			(layer "B.SilkS")
		)
		(fp_line
			(start -0.67945 -0.3048)
			(end -0.67945 0.3048)
			(stroke
				(width 0.1)
				(type default)
			)
			(layer "B.Fab")
		)
		(fp_line
			(start -0.67945 0.3048)
			(end -0.120396 0.3048)
			(stroke
				(width 0.1)
				(type default)
			)
			(layer "B.Fab")
		)
		(fp_line
			(start -0.12065 -0.3048)
			(end -0.67945 -0.3048)
			(stroke
				(width 0.1)
				(type default)
			)
			(layer "B.Fab")
		)
		(fp_line
			(start -0.12065 -0.2794)
			(end -0.12065 -0.3048)
			(stroke
				(width 0.1)
				(type default)
			)
			(layer "B.Fab")
		)
		(fp_line
			(start -0.120396 0.2794)
			(end 0.12065 0.2794)
			(stroke
				(width 0.1)
				(type default)
			)
			(layer "B.Fab")
		)
		(fp_line
			(start -0.120396 0.3048)
			(end -0.120396 0.2794)
			(stroke
				(width 0.1)
				(type default)
			)
			(layer "B.Fab")
		)
		(fp_line
			(start 0.12065 -0.305054)
			(end 0.12065 -0.2794)
			(stroke
				(width 0.1)
				(type default)
			)
			(layer "B.Fab")
		)
		(fp_line
			(start 0.12065 -0.2794)
			(end -0.12065 -0.2794)
			(stroke
				(width 0.1)
				(type default)
			)
			(layer "B.Fab")
		)
		(fp_line
			(start 0.12065 0.2794)
			(end 0.12065 0.3048)
			(stroke
				(width 0.1)
				(type default)
			)
			(layer "B.Fab")
		)
		(fp_line
			(start 0.12065 0.3048)
			(end 0.67945 0.3048)
			(stroke
				(width 0.1)
				(type default)
			)
			(layer "B.Fab")
		)
		(fp_line
			(start 0.67945 -0.305054)
			(end 0.12065 -0.305054)
			(stroke
				(width 0.1)
				(type default)
			)
			(layer "B.Fab")
		)
		(fp_line
			(start 0.67945 0.3048)
			(end 0.67945 -0.305054)
			(stroke
				(width 0.1)
				(type default)
			)
			(layer "B.Fab")
		)
		(pad "1" smd circle
			(at 0.40005 0 180)
			(size 0 0)
			(layers "B.Cu" "B.Mask" "B.Paste")
			(net "P12V_AUX")
		)
		(pad "2" smd circle
			(at -0.40005 0 180)
			(size 0 0)
			(layers "B.Cu" "B.Mask" "B.Paste")
			(net "HSC_VOSEN")
		)
	)
)
